FILE_TYPE = CONNECTIVITY;
{Allegro Design Entry HDL 17.4-2019 S026 (4007227) 1/17/2022}
"PAGE_NUMBER" = 70;
0"NC";
1"PVDD_33_S5\g";
2"GND\g";
3"GND\g";
4"PVDD18_S5_P0\g";
5"PVDD18_S5_P0\g";
6"GND\g";
%"Q_CAP"
"1","(-8600,3100)","0","pure_quanta","I1";
;
LOCATION"C2514"
$SEC"1"
CDS_SEC"1"
PACK_TYPE"C0402"
VOLTAGE"4V"
VALUE"22UF"
TOLERANCE"20%"
MATERIAL"X6S"
CDS_LIB"pure_quanta"
PART_NUMBER"CH622KMEB02";
"B"
$PN"2"6;
"A"
$PN"1"4;
%"Q_CAP"
"1","(-7700,3875)","0","pure_quanta","I10";
;
LOCATION"C2518"
$SEC"1"
CDS_SEC"1"
PACK_TYPE"C0402"
VOLTAGE"4V"
VALUE"22UF"
TOLERANCE"20%"
MATERIAL"X6S"
CDS_LIB"pure_quanta"
PART_NUMBER"CH622KMEB02";
"B"
$PN"2"3;
"A"
$PN"1"5;
%"Q_CAP"
"1","(-7250,3875)","0","pure_quanta","I11";
;
LOCATION"C2520"
$SEC"1"
CDS_SEC"1"
PACK_TYPE"C0402"
VOLTAGE"4V"
VALUE"22UF"
TOLERANCE"20%"
MATERIAL"X6S"
CDS_LIB"pure_quanta"
PART_NUMBER"CH622KMEB02";
"B"
$PN"2"3;
"A"
$PN"1"5;
%"Q_CAP"
"1","(-6800,3875)","0","pure_quanta","I12";
;
LOCATION"C2521"
$SEC"1"
CDS_SEC"1"
PACK_TYPE"C0402"
VOLTAGE"4V"
VALUE"22UF"
TOLERANCE"20%"
MATERIAL"X6S"
CDS_LIB"pure_quanta"
PART_NUMBER"CH622KMEB02";
"B"
$PN"2"3;
"A"
$PN"1"5;
%"Q_CAP"
"1","(-6350,3875)","0","pure_quanta","I13";
;
LOCATION"C2522"
$SEC"1"
CDS_SEC"1"
PACK_TYPE"C0402"
VOLTAGE"4V"
VALUE"22UF"
TOLERANCE"20%"
MATERIAL"X6S"
CDS_LIB"pure_quanta"
PART_NUMBER"CH622KMEB02";
"B"
$PN"2"3;
"A"
$PN"1"5;
%"Q_CAP"
"1","(-5900,3875)","0","pure_quanta","I14";
;
LOCATION"C2523"
$SEC"1"
CDS_SEC"1"
PACK_TYPE"C0402"
VOLTAGE"4V"
VALUE"22UF"
TOLERANCE"20%"
MATERIAL"X6S"
CDS_LIB"pure_quanta"
PART_NUMBER"CH622KMEB02";
"B"
$PN"2"3;
"A"
$PN"1"5;
%"Q_CAP"
"1","(-5450,3875)","0","pure_quanta","I15";
;
LOCATION"C2524"
$SEC"1"
CDS_SEC"1"
PACK_TYPE"C0402"
VOLTAGE"4V"
VALUE"22UF"
TOLERANCE"20%"
MATERIAL"X6S"
CDS_LIB"pure_quanta"
PART_NUMBER"CH622KMEB02";
"B"
$PN"2"3;
"A"
$PN"1"5;
%"Q_CAP"
"1","(-5000,3875)","0","pure_quanta","I16";
;
LOCATION"C2525"
$SEC"1"
CDS_SEC"1"
PACK_TYPE"C0402"
VOLTAGE"4V"
VALUE"22UF"
TOLERANCE"20%"
MATERIAL"X6S"
CDS_LIB"pure_quanta"
PART_NUMBER"CH622KMEB02";
"B"
$PN"2"3;
"A"
$PN"1"5;
%"UNIVERSAL_GND"
"1","(-4600,3500)","0","pure_quanta_power","I17";
;
CDS_LIB"pure_quanta_power"
HDL_POWER"GND";
"A"3;
%"Q_CAP"
"1","(-4600,3875)","0","pure_quanta","I18";
;
LOCATION"C2526"
$SEC"1"
CDS_SEC"1"
PACK_TYPE"C0402"
VOLTAGE"4V"
VALUE"22UF"
TOLERANCE"20%"
MATERIAL"X6S"
CDS_LIB"pure_quanta"
PART_NUMBER"CH622KMEB02";
"B"
$PN"2"3;
"A"
$PN"1"5;
%"UNIVERSAL_POWER"
"1","(-8600,3375)","0","pure_quanta_power","I2";
;
HDL_POWER"PVDD18_S5_P0"
CDS_LIB"pure_quanta_power";
"A"4;
%"UNIVERSAL_POWER"
"1","(-8525,5800)","0","pure_quanta_power","I23";
;
HDL_POWER"PVDD_33_S5"
CDS_LIB"pure_quanta_power";
"A"1;
%"UNIVERSAL_GND"
"1","(-8075,5150)","0","pure_quanta_power","I24";
;
CDS_LIB"pure_quanta_power"
HDL_POWER"GND";
"A"2;
%"Q_CAP"
"1","(-8075,5525)","0","pure_quanta","I25";
;
LOCATION"C2515"
$SEC"1"
CDS_SEC"1"
TOLERANCE"20%"
PACK_TYPE"C0402"
VALUE"10UF"
VOLTAGE"6.3V"
MATERIAL"X6S"
CDS_LIB"pure_quanta"
PART_NUMBER"CH6101MEB01";
"B"
$PN"2"2;
"A"
$PN"1"1;
%"Q_CAP"
"1","(-8525,5525)","0","pure_quanta","I26";
;
LOCATION"C2512"
$SEC"1"
CDS_SEC"1"
PACK_TYPE"C0402"
TOLERANCE"20%"
VALUE"10UF"
VOLTAGE"6.3V"
MATERIAL"X6S"
CDS_LIB"pure_quanta"
PART_NUMBER"CH6101MEB01";
"B"
$PN"2"2;
"A"
$PN"1"1;
%"Q_CAP"
"1","(-8600,3875)","0","pure_quanta","I3";
;
LOCATION"C2513"
$SEC"1"
CDS_SEC"1"
PACK_TYPE"C0402"
VOLTAGE"4V"
VALUE"22UF"
TOLERANCE"20%"
MATERIAL"X6S"
CDS_LIB"pure_quanta"
PART_NUMBER"CH622KMEB02";
"B"
$PN"2"3;
"A"
$PN"1"5;
%"UNIVERSAL_POWER"
"1","(-8600,4150)","0","pure_quanta_power","I4";
;
HDL_POWER"PVDD18_S5_P0"
CDS_LIB"pure_quanta_power";
"A"5;
%"UNIVERSAL_GND"
"1","(-8150,2750)","0","pure_quanta_power","I7";
;
CDS_LIB"pure_quanta_power"
HDL_POWER"GND";
"A"6;
%"Q_CAP"
"1","(-8150,3100)","0","pure_quanta","I8";
;
LOCATION"C2517"
$SEC"1"
CDS_SEC"1"
PACK_TYPE"C0402"
VOLTAGE"4V"
VALUE"22UF"
TOLERANCE"20%"
MATERIAL"X6S"
CDS_LIB"pure_quanta"
PART_NUMBER"CH622KMEB02";
"B"
$PN"2"6;
"A"
$PN"1"4;
%"Q_CAP"
"1","(-8150,3875)","0","pure_quanta","I9";
;
LOCATION"C2516"
$SEC"1"
CDS_SEC"1"
PACK_TYPE"C0402"
VOLTAGE"4V"
VALUE"22UF"
TOLERANCE"20%"
MATERIAL"X6S"
CDS_LIB"pure_quanta"
PART_NUMBER"CH622KMEB02";
"B"
$PN"2"3;
"A"
$PN"1"5;
END.
